# SCM (Grand Teton) — schematic netlist excerpt (pin names and nets, part order shuffled) for the footprints in the layout excerpt that follows; sources: Cadence DE-HDL packaged netlist, KiCad conversion of 12092022_DA0F0TMDCD0_F0T_Management_Board_D_brd_V3_OCP.brd

R811  Q_RES  0 5% EMPTY  pkg 0402LF  page 10 : A = PCH_BEEP_LED ; B = PCH_BEEP_R_LED
R716  Q_RES  10K 1% CHIP  pkg 0402LF  page 17 : A = P5V_AUX ; B = LPC_ESPI_SEL_N

(kicad_pcb
	(version 20260206)
	(generator "pcbnew")
	(generator_version "10.0")
	(general
		(thickness 1.6)
		(legacy_teardrops no)
	)
	(paper "A4")
	(title_block
		(title "12092022_DA0F0TMDCD0_F0T_Management_Board_D_brd_V3_OCP.brd")
		(comment 1 "Grand Teton / footprints 1133-1134 of 1440")
	)
	(layers
		(0 "F.Cu" signal "TOP")
		(4 "In1.Cu" signal "GND")
		(6 "In2.Cu" signal "IN1")
		(8 "In3.Cu" signal "GND1")
		(10 "In4.Cu" signal "IN2")
		(12 "In5.Cu" signal "VCC")
		(14 "In6.Cu" signal "VCC1")
		(16 "In7.Cu" signal "IN3")
		(18 "In8.Cu" signal "GND2")
		(20 "In9.Cu" signal "IN4")
		(22 "In10.Cu" signal "GND3")
		(2 "B.Cu" signal "BOTTOM")
		(9 "F.Adhes" user "F.Adhesive")
		(11 "B.Adhes" user "B.Adhesive")
		(13 "F.Paste" user "Package Geometry/Pastemask Top")
		(15 "B.Paste" user "Package Geometry/Pastemask Bottom")
		(5 "F.SilkS" user "Ref Des/Silkscreen Top")
		(7 "B.SilkS" user "Ref Des/Silkscreen Bottom")
		(1 "F.Mask" user "Board Geometry/Soldermask Top")
		(3 "B.Mask" user "Board Geometry/Soldermask Bottom")
		(17 "Dwgs.User" user "User.Drawings")
		(19 "Cmts.User" user "User.Comments")
		(21 "Eco1.User" user "User.Eco1")
		(23 "Eco2.User" user "User.Eco2")
		(25 "Edge.Cuts" user "Board Geometry/Outline")
		(27 "Margin" user)
		(31 "F.CrtYd" user "Package Geometry/Place Bound Top")
		(29 "B.CrtYd" user "Package Geometry/Place Bound Bottom")
		(35 "F.Fab" user "Ref Des/Assembly Top")
		(33 "B.Fab" user "Ref Des/Assembly Bottom")
	)
	(footprint ""
		(layer "B.Cu")
		(at 10.2616 -106.3752 -90)
		(property "Reference" "R811"
			(at 0 0 90)
			(layer "B.SilkS")
			(hide yes)
			(effects
				(font
					(size 1.27 1.27)
				)
				(justify mirror)
			)
		)
		(property "Value" ""
			(at 0 0 90)
			(layer "B.Fab")
			(effects
				(font
					(size 1.27 1.27)
				)
				(justify mirror)
			)
		)
		(duplicate_pad_numbers_are_jumpers no)
		(fp_line
			(start -0.7874 0.4064)
			(end 0.7874 0.4064)
			(stroke
				(width 0.1524)
				(type default)
			)
			(layer "B.SilkS")
		)
		(fp_line
			(start 0.7874 0.4064)
			(end 0.7874 -0.4064)
			(stroke
				(width 0.1524)
				(type default)
			)
			(layer "B.SilkS")
		)
		(fp_line
			(start -0.7874 -0.4064)
			(end -0.7874 0.4064)
			(stroke
				(width 0.1524)
				(type default)
			)
			(layer "B.SilkS")
		)
		(fp_line
			(start 0.7874 -0.4064)
			(end -0.7874 -0.4064)
			(stroke
				(width 0.1524)
				(type default)
			)
			(layer "B.SilkS")
		)
		(fp_line
			(start -0.67945 0.3048)
			(end -0.120396 0.3048)
			(stroke
				(width 0.1)
				(type default)
			)
			(layer "B.Fab")
		)
		(fp_line
			(start -0.120396 0.3048)
			(end -0.120396 0.2794)
			(stroke
				(width 0.1)
				(type default)
			)
			(layer "B.Fab")
		)
		(fp_line
			(start 0.12065 0.3048)
			(end 0.67945 0.3048)
			(stroke
				(width 0.1)
				(type default)
			)
			(layer "B.Fab")
		)
		(fp_line
			(start 0.67945 0.3048)
			(end 0.67945 -0.305054)
			(stroke
				(width 0.1)
				(type default)
			)
			(layer "B.Fab")
		)
		(fp_line
			(start -0.120396 0.2794)
			(end 0.12065 0.2794)
			(stroke
				(width 0.1)
				(type default)
			)
			(layer "B.Fab")
		)
		(fp_line
			(start 0.12065 0.2794)
			(end 0.12065 0.3048)
			(stroke
				(width 0.1)
				(type default)
			)
			(layer "B.Fab")
		)
		(fp_line
			(start -0.12065 -0.2794)
			(end -0.12065 -0.3048)
			(stroke
				(width 0.1)
				(type default)
			)
			(layer "B.Fab")
		)
		(fp_line
			(start 0.12065 -0.2794)
			(end -0.12065 -0.2794)
			(stroke
				(width 0.1)
				(type default)
			)
			(layer "B.Fab")
		)
		(fp_line
			(start -0.67945 -0.3048)
			(end -0.67945 0.3048)
			(stroke
				(width 0.1)
				(type default)
			)
			(layer "B.Fab")
		)
		(fp_line
			(start -0.12065 -0.3048)
			(end -0.67945 -0.3048)
			(stroke
				(width 0.1)
				(type default)
			)
			(layer "B.Fab")
		)
		(fp_line
			(start 0.12065 -0.305054)
			(end 0.12065 -0.2794)
			(stroke
				(width 0.1)
				(type default)
			)
			(layer "B.Fab")
		)
		(fp_line
			(start 0.67945 -0.305054)
			(end 0.12065 -0.305054)
			(stroke
				(width 0.1)
				(type default)
			)
			(layer "B.Fab")
		)
		(pad "1" smd circle
			(at 0.40005 0 90)
			(size 0 0)
			(layers "B.Cu" "B.Mask" "B.Paste")
			(net "PCH_BEEP_LED")
		)
		(pad "2" smd circle
			(at -0.40005 0 90)
			(size 0 0)
			(layers "B.Cu" "B.Mask" "B.Paste")
			(net "PCH_BEEP_R_LED")
		)
	)
	(footprint ""
		(layer "B.Cu")
		(at 78.74 -94.742)
		(property "Reference" "R716"
			(at 0 0 0)
			(layer "B.SilkS")
			(hide yes)
			(effects
				(font
					(size 1.27 1.27)
				)
				(justify mirror)
			)
		)
		(property "Value" ""
			(at 0 0 0)
			(layer "B.Fab")
			(effects
				(font
					(size 1.27 1.27)
				)
				(justify mirror)
			)
		)
		(duplicate_pad_numbers_are_jumpers no)
		(fp_line
			(start -0.7874 -0.4064)
			(end -0.7874 0.4064)
			(stroke
				(width 0.1524)
				(type default)
			)
			(layer "B.SilkS")
		)
		(fp_line
			(start -0.7874 0.4064)
			(end 0.7874 0.4064)
			(stroke
				(width 0.1524)
				(type default)
			)
			(layer "B.SilkS")
		)
		(fp_line
			(start 0.7874 -0.4064)
			(end -0.7874 -0.4064)
			(stroke
				(width 0.1524)
				(type default)
			)
			(layer "B.SilkS")
		)
		(fp_line
			(start 0.7874 0.4064)
			(end 0.7874 -0.4064)
			(stroke
				(width 0.1524)
				(type default)
			)
			(layer "B.SilkS")
		)
		(fp_line
			(start -0.67945 -0.3048)
			(end -0.67945 0.3048)
			(stroke
				(width 0.1)
				(type default)
			)
			(layer "B.Fab")
		)
		(fp_line
			(start -0.67945 0.3048)
			(end -0.120396 0.3048)
			(stroke
				(width 0.1)
				(type default)
			)
			(layer "B.Fab")
		)
		(fp_line
			(start -0.12065 -0.3048)
			(end -0.67945 -0.3048)
			(stroke
				(width 0.1)
				(type default)
			)
			(layer "B.Fab")
		)
		(fp_line
			(start -0.12065 -0.2794)
			(end -0.12065 -0.3048)
			(stroke
				(width 0.1)
				(type default)
			)
			(layer "B.Fab")
		)
		(fp_line
			(start -0.120396 0.2794)
			(end 0.12065 0.2794)
			(stroke
				(width 0.1)
				(type default)
			)
			(layer "B.Fab")
		)
		(fp_line
			(start -0.120396 0.3048)
			(end -0.120396 0.2794)
			(stroke
				(width 0.1)
				(type default)
			)
			(layer "B.Fab")
		)
		(fp_line
			(start 0.12065 -0.305054)
			(end 0.12065 -0.2794)
			(stroke
				(width 0.1)
				(type default)
			)
			(layer "B.Fab")
		)
		(fp_line
			(start 0.12065 -0.2794)
			(end -0.12065 -0.2794)
			(stroke
				(width 0.1)
				(type default)
			)
			(layer "B.Fab")
		)
		(fp_line
			(start 0.12065 0.2794)
			(end 0.12065 0.3048)
			(stroke
				(width 0.1)
				(type default)
			)
			(layer "B.Fab")
		)
		(fp_line
			(start 0.12065 0.3048)
			(end 0.67945 0.3048)
			(stroke
				(width 0.1)
				(type default)
			)
			(layer "B.Fab")
		)
		(fp_line
			(start 0.67945 -0.305054)
			(end 0.12065 -0.305054)
			(stroke
				(width 0.1)
				(type default)
			)
			(layer "B.Fab")
		)
		(fp_line
			(start 0.67945 0.3048)
			(end 0.67945 -0.305054)
			(stroke
				(width 0.1)
				(type default)
			)
			(layer "B.Fab")
		)
		(pad "1" smd circle
			(at 0.40005 0 180)
			(size 0 0)
			(layers "B.Cu" "B.Mask" "B.Paste")
			(net "P5V_AUX")
		)
		(pad "2" smd circle
			(at -0.40005 0 180)
			(size 0 0)
			(layers "B.Cu" "B.Mask" "B.Paste")
			(net "LPC_ESPI_SEL_N")
		)
	)
)
